# TIMECARD (Time Appliance Project (Time Card)) — schematic netlist excerpt (pin names and nets, part order shuffled) for the footprints in the layout excerpt that follows; sources: Cadence DE-HDL packaged netlist, KiCad conversion of R4006-B0001-02_R01.brd

R17  RESISTOR  20OHM 1%  pkg SMC_0402R_H016  page 28 : \1\ = XP3R3V ; \2\ = UNNAMED_517_CAPACITOR_I30_1
R8  RESISTOR  0OHM -  pkg SMC_0402R_H016  page 27 : \1\ = SG ; \2\ = UNNAMED_15_MP5022CGQVZQFN22_I21
TP42  TP_PIONT  pkg TP010CT020B030_PTH  page 25 : \1\ = XP12R0V_IN

(kicad_pcb
	(version 20260206)
	(generator "pcbnew")
	(generator_version "10.0")
	(general
		(thickness 1.6)
		(legacy_teardrops no)
	)
	(paper "A4")
	(title_block
		(title "timecard-production-celestica-r4006 — R4006-B0001-02_R01.brd")
		(comment 1 "Time Appliance Project (Time Card) / footprints 224-226 of 1113")
	)
	(layers
		(0 "F.Cu" signal "TOP")
		(4 "In1.Cu" signal "L02_GND1")
		(6 "In2.Cu" signal "L03_SIG1")
		(8 "In3.Cu" signal "L04_GND2")
		(10 "In4.Cu" signal "L05_VCC1")
		(12 "In5.Cu" signal "L06_VCC2")
		(14 "In6.Cu" signal "L07_GND3")
		(16 "In7.Cu" signal "L08_SIG2")
		(18 "In8.Cu" signal "L09_GND4")
		(2 "B.Cu" signal "BOTTOM")
		(9 "F.Adhes" user "F.Adhesive")
		(11 "B.Adhes" user "B.Adhesive")
		(13 "F.Paste" user "Package Geometry/Pastemask Top")
		(15 "B.Paste" user "Package Geometry/Pastemask Bottom")
		(5 "F.SilkS" user "Ref Des/Silkscreen Top")
		(7 "B.SilkS" user "Ref Des/Silkscreen Bottom")
		(1 "F.Mask" user "Board Geometry/Soldermask Top")
		(3 "B.Mask" user "Board Geometry/Soldermask Bottom")
		(17 "Dwgs.User" user "User.Drawings")
		(19 "Cmts.User" user "User.Comments")
		(21 "Eco1.User" user "User.Eco1")
		(23 "Eco2.User" user "User.Eco2")
		(25 "Edge.Cuts" user "Board Geometry/Outline")
		(27 "Margin" user)
		(31 "F.CrtYd" user "Package Geometry/Place Bound Top")
		(29 "B.CrtYd" user "Package Geometry/Place Bound Bottom")
		(35 "F.Fab" user "Ref Des/Assembly Top")
		(33 "B.Fab" user "Ref Des/Assembly Bottom")
	)
	(footprint ""
		(layer "F.Cu")
		(at 145.8214 -93.1418 180)
		(property "Reference" "R8"
			(at 0.2794 -8.72617 0)
			(unlocked yes)
			(layer "F.SilkS")
			(effects
				(font
					(size 0.7874 0.5842)
					(thickness 0.1524)
				)
			)
		)
		(property "Value" "VAL*"
			(at 0.02032 2.13233 180)
			(unlocked yes)
			(layer "F.Fab")
			(hide yes)
			(effects
				(font
					(size 0.7874 0.5842)
					(thickness 0.1524)
				)
			)
		)
		(property "Device Type" "RESISTOR-G155-100R0-J0,0OHM,-"
			(at 0.008382 1.210564 180)
			(unlocked yes)
			(layer "F.Fab")
			(hide yes)
			(effects
				(font
					(size 0.7874 0.5842)
					(thickness 0.1524)
				)
			)
		)
		(property "User Part Number" "PARTNUM*"
			(at 0.02032 4.024884 180)
			(unlocked yes)
			(layer "Cmts.User")
			(hide yes)
			(effects
				(font
					(size 0.7874 0.5842)
					(thickness 0.1524)
				)
			)
		)
		(property "Tolerance" "TOL*"
			(at 0.044704 3.05435 180)
			(unlocked yes)
			(layer "Cmts.User")
			(hide yes)
			(effects
				(font
					(size 0.7874 0.5842)
					(thickness 0.1524)
				)
			)
		)
		(duplicate_pad_numbers_are_jumpers no)
		(fp_line
			(start 1.143 0.5588)
			(end 1.143 -0.5588)
			(stroke
				(width 0.1)
				(type default)
			)
			(layer "F.SilkS")
		)
		(fp_line
			(start 1.143 -0.5588)
			(end -1.143 -0.5588)
			(stroke
				(width 0.1)
				(type default)
			)
			(layer "F.SilkS")
		)
		(fp_line
			(start -1.143 0.5588)
			(end 1.143 0.5588)
			(stroke
				(width 0.1)
				(type default)
			)
			(layer "F.SilkS")
		)
		(fp_line
			(start -1.143 -0.5588)
			(end -1.143 0.5588)
			(stroke
				(width 0.1)
				(type default)
			)
			(layer "F.SilkS")
		)
		(fp_rect
			(start 1.143 -0.5588)
			(end -1.143 0.5588)
			(stroke
				(width 0)
				(type default)
			)
			(fill no)
			(layer "F.CrtYd")
		)
		(fp_line
			(start 0.508 0.3048)
			(end 0.508 -0.3048)
			(stroke
				(width 0.1)
				(type default)
			)
			(layer "F.Fab")
		)
		(fp_line
			(start 0.508 -0.3048)
			(end -0.508 -0.3048)
			(stroke
				(width 0.1)
				(type default)
			)
			(layer "F.Fab")
		)
		(fp_line
			(start -0.508 0.3048)
			(end 0.508 0.3048)
			(stroke
				(width 0.1)
				(type default)
			)
			(layer "F.Fab")
		)
		(fp_line
			(start -0.508 -0.3048)
			(end -0.508 0.3048)
			(stroke
				(width 0.1)
				(type default)
			)
			(layer "F.Fab")
		)
		(pad "1" smd rect
			(at -0.5334 0 180)
			(size 0.7112 0.6096)
			(layers "F.Cu" "F.Mask" "F.Paste")
			(net "SG")
		)
		(pad "2" smd rect
			(at 0.5334 0 180)
			(size 0.7112 0.6096)
			(layers "F.Cu" "F.Mask" "F.Paste")
			(net "UNNAMED_15_MP5022CGQVZQFN22_I21")
		)
		(zone
			(layer "F.Cu")
			(hatch none 0.5)
			(connect_pads
				(clearance 0)
			)
			(min_thickness 0.25)
			(keepout
				(tracks allowed)
				(vias not_allowed)
				(pads allowed)
				(copperpour not_allowed)
				(footprints allowed)
			)
			(placement
				(enabled no)
				(sheetname "")
			)
			(fill
				(thermal_gap 0.5)
				(thermal_bridge_width 0.5)
				(island_removal_mode 0)
			)
			(polygon
				(pts
					(xy 145.7452 -92.837) (xy 145.8976 -92.837) (xy 145.8976 -93.4466) (xy 145.7452 -93.4466)
				)
			)
		)
	)
	(footprint ""
		(layer "F.Cu")
		(at 24.8412 -99.5172)
		(property "Reference" "TP42"
			(at 0.72517 -1.2446 90)
			(unlocked yes)
			(layer "F.SilkS")
			(effects
				(font
					(size 0.7874 0.5842)
					(thickness 0.1524)
				)
				(justify left)
			)
		)
		(property "Value" ""
			(at 0 0 0)
			(layer "F.Fab")
			(effects
				(font
					(size 1.27 1.27)
				)
			)
		)
		(property "Device Type" "TP_PIONT-TP010CT020B030_PTH-TPA"
			(at -1.341882 0.996696 0)
			(unlocked yes)
			(layer "F.Fab")
			(hide yes)
			(effects
				(font
					(size 0.7874 0.5842)
					(thickness 0.000001)
				)
				(justify left)
			)
		)
		(duplicate_pad_numbers_are_jumpers no)
		(fp_poly
			(pts
				(arc
					(start 0.889 0)
					(mid -0.889 0)
					(end 0.889 0)
				)
			)
			(stroke
				(width 0)
				(type default)
			)
			(fill no)
			(layer "B.CrtYd")
		)
		(fp_poly
			(pts
				(arc
					(start 0.889 0)
					(mid -0.889 0)
					(end 0.889 0)
				)
			)
			(stroke
				(width 0)
				(type default)
			)
			(fill no)
			(layer "F.CrtYd")
		)
		(pad "1" thru_hole circle
			(at 0 0)
			(size 0.508 0.508)
			(drill 0.254)
			(layers "*.Cu" "*.Mask")
			(remove_unused_layers no)
			(net "XP12R0V_IN")
			(clearance 0.1016)
			(padstack
				(mode front_inner_back)
				(layer "Inner"
					(shape circle)
					(size 0.508 0.508)
					(clearance 0.1016)
				)
				(layer "B.Cu"
					(shape circle)
					(size 0.762 0.762)
					(clearance -0.0254)
				)
			)
		)
	)
	(footprint ""
		(layer "F.Cu")
		(at 92.0242 -97.9678 90)
		(property "Reference" "R17"
			(at -0.0508 1.36017 90)
			(unlocked yes)
			(layer "F.SilkS")
			(effects
				(font
					(size 0.7874 0.5842)
					(thickness 0.1524)
				)
			)
		)
		(property "Value" "VAL*"
			(at 0.02032 2.13233 90)
			(unlocked yes)
			(layer "F.Fab")
			(hide yes)
			(effects
				(font
					(size 0.7874 0.5842)
					(thickness 0.1524)
				)
			)
		)
		(property "Tolerance" "TOL*"
			(at 0.044704 3.05435 90)
			(unlocked yes)
			(layer "Cmts.User")
			(hide yes)
			(effects
				(font
					(size 0.7874 0.5842)
					(thickness 0.1524)
				)
			)
		)
		(property "User Part Number" "PARTNUM*"
			(at 0.02032 4.024884 90)
			(unlocked yes)
			(layer "Cmts.User")
			(hide yes)
			(effects
				(font
					(size 0.7874 0.5842)
					(thickness 0.1524)
				)
			)
		)
		(property "Device Type" "RESISTOR-G155-120R0-01,20OHM,1%"
			(at 0.008382 1.210564 90)
			(unlocked yes)
			(layer "F.Fab")
			(hide yes)
			(effects
				(font
					(size 0.7874 0.5842)
					(thickness 0.1524)
				)
			)
		)
		(duplicate_pad_numbers_are_jumpers no)
		(fp_line
			(start 1.143 -0.5588)
			(end -1.143 -0.5588)
			(stroke
				(width 0.1)
				(type default)
			)
			(layer "F.SilkS")
		)
		(fp_line
			(start -1.143 -0.5588)
			(end -1.143 0.5588)
			(stroke
				(width 0.1)
				(type default)
			)
			(layer "F.SilkS")
		)
		(fp_line
			(start 1.143 0.5588)
			(end 1.143 -0.5588)
			(stroke
				(width 0.1)
				(type default)
			)
			(layer "F.SilkS")
		)
		(fp_line
			(start -1.143 0.5588)
			(end 1.143 0.5588)
			(stroke
				(width 0.1)
				(type default)
			)
			(layer "F.SilkS")
		)
		(fp_rect
			(start -1.143 -0.5588)
			(end 1.143 0.5588)
			(stroke
				(width 0)
				(type default)
			)
			(fill no)
			(layer "F.CrtYd")
		)
		(fp_line
			(start 0.508 -0.3048)
			(end -0.508 -0.3048)
			(stroke
				(width 0.1)
				(type default)
			)
			(layer "F.Fab")
		)
		(fp_line
			(start -0.508 -0.3048)
			(end -0.508 0.3048)
			(stroke
				(width 0.1)
				(type default)
			)
			(layer "F.Fab")
		)
		(fp_line
			(start 0.508 0.3048)
			(end 0.508 -0.3048)
			(stroke
				(width 0.1)
				(type default)
			)
			(layer "F.Fab")
		)
		(fp_line
			(start -0.508 0.3048)
			(end 0.508 0.3048)
			(stroke
				(width 0.1)
				(type default)
			)
			(layer "F.Fab")
		)
		(pad "1" smd rect
			(at -0.5334 0 90)
			(size 0.7112 0.6096)
			(layers "F.Cu" "F.Mask" "F.Paste")
			(net "XP3R3V")
		)
		(pad "2" smd rect
			(at 0.5334 0 90)
			(size 0.7112 0.6096)
			(layers "F.Cu" "F.Mask" "F.Paste")
			(net "UNNAMED_517_CAPACITOR_I30_1")
		)
		(zone
			(layer "F.Cu")
			(hatch none 0.5)
			(connect_pads
				(clearance 0)
			)
			(min_thickness 0.25)
			(keepout
				(tracks allowed)
				(vias not_allowed)
				(pads allowed)
				(copperpour not_allowed)
				(footprints allowed)
			)
			(placement
				(enabled no)
				(sheetname "")
			)
			(fill
				(thermal_gap 0.5)
				(thermal_bridge_width 0.5)
				(island_removal_mode 0)
			)
			(polygon
				(pts
					(xy 91.7194 -97.8916) (xy 92.329 -97.8916) (xy 92.329 -98.044) (xy 91.7194 -98.044)
				)
			)
		)
	)
)
